# S9S_MB_2U (Grand Teton) — schematic netlist excerpt (pin names and nets, part order shuffled) for the footprints in the layout excerpt that follows; sources: Cadence DE-HDL packaged netlist, KiCad conversion of 03242023_DA0F0TMBIJ0_F0T_Motherboard_J_brd_V01_OCP.brd

R1465  Q_RES  10K 1% EMPTY  pkg 0402LF  page 215 : A = P3V3_AUX ; B = IRQ_BMC_CPU_NMI_R1
C303  Q_CAP  22UF 4V 20% X6S  pkg C0402  page 77 : A = PVCCIN_CPU1 ; B = GND
C1527  Q_CAP_DIFFBUS  DIFF BUS_0.22UF 6.3V 20% X6S  pkg C0201  page 177 : \1\ = P5E_CPU1_PE3_TX_C_DP<10> ; \2\ = P5E_CPU1_PE3_TX_DP<10>

(kicad_pcb
	(version 20260206)
	(generator "pcbnew")
	(generator_version "10.0")
	(general
		(thickness 1.6)
		(legacy_teardrops no)
	)
	(paper "A4")
	(title_block
		(title "03242023_DA0F0TMBIJ0_F0T_Motherboard_J_brd_V01_OCP.brd")
		(comment 1 "Grand Teton / footprints 2449-2451 of 6105")
	)
	(layers
		(0 "F.Cu" signal "TOP")
		(4 "In1.Cu" signal "GND")
		(6 "In2.Cu" signal "IN1")
		(8 "In3.Cu" signal "GND1")
		(10 "In4.Cu" signal "IN2")
		(12 "In5.Cu" signal "GND2")
		(14 "In6.Cu" signal "IN3")
		(16 "In7.Cu" signal "GND3")
		(18 "In8.Cu" signal "VCC")
		(20 "In9.Cu" signal "VCC1")
		(22 "In10.Cu" signal "GND4")
		(24 "In11.Cu" signal "IN4")
		(26 "In12.Cu" signal "GND5")
		(28 "In13.Cu" signal "IN5")
		(30 "In14.Cu" signal "GND6")
		(32 "In15.Cu" signal "IN6")
		(34 "In16.Cu" signal "GND7")
		(2 "B.Cu" signal "BOTTOM")
		(9 "F.Adhes" user "F.Adhesive")
		(11 "B.Adhes" user "B.Adhesive")
		(13 "F.Paste" user "Package Geometry/Pastemask Top")
		(15 "B.Paste" user "Package Geometry/Pastemask Bottom")
		(5 "F.SilkS" user "Ref Des/Silkscreen Top")
		(7 "B.SilkS" user "Ref Des/Silkscreen Bottom")
		(1 "F.Mask" user "Board Geometry/Soldermask Top")
		(3 "B.Mask" user "Board Geometry/Soldermask Bottom")
		(17 "Dwgs.User" user "User.Drawings")
		(19 "Cmts.User" user "User.Comments")
		(21 "Eco1.User" user "User.Eco1")
		(23 "Eco2.User" user "User.Eco2")
		(25 "Edge.Cuts" user "Board Geometry/Outline")
		(27 "Margin" user)
		(31 "F.CrtYd" user "Package Geometry/Place Bound Top")
		(29 "B.CrtYd" user "Package Geometry/Place Bound Bottom")
		(35 "F.Fab" user "Ref Des/Assembly Top")
		(33 "B.Fab" user "Ref Des/Assembly Bottom")
	)
	(footprint ""
		(layer "F.Cu")
		(at 197.19036 -115.534948 180)
		(property "Reference" "R1465"
			(at 0 0 180)
			(layer "F.SilkS")
			(hide yes)
			(effects
				(font
					(size 1.27 1.27)
				)
			)
		)
		(property "Value" ""
			(at 0 0 180)
			(layer "F.Fab")
			(effects
				(font
					(size 1.27 1.27)
				)
			)
		)
		(duplicate_pad_numbers_are_jumpers no)
		(fp_line
			(start 0.7874 0.4064)
			(end -0.7874 0.4064)
			(stroke
				(width 0.1524)
				(type default)
			)
			(layer "F.SilkS")
		)
		(fp_line
			(start 0.7874 -0.4064)
			(end 0.7874 0.4064)
			(stroke
				(width 0.1524)
				(type default)
			)
			(layer "F.SilkS")
		)
		(fp_line
			(start -0.7874 0.4064)
			(end -0.7874 -0.4064)
			(stroke
				(width 0.1524)
				(type default)
			)
			(layer "F.SilkS")
		)
		(fp_line
			(start -0.7874 -0.4064)
			(end 0.7874 -0.4064)
			(stroke
				(width 0.1524)
				(type default)
			)
			(layer "F.SilkS")
		)
		(fp_line
			(start 0.67945 0.3048)
			(end 0.120396 0.3048)
			(stroke
				(width 0.1)
				(type default)
			)
			(layer "F.Fab")
		)
		(fp_line
			(start 0.67945 -0.3048)
			(end 0.67945 0.3048)
			(stroke
				(width 0.1)
				(type default)
			)
			(layer "F.Fab")
		)
		(fp_line
			(start 0.12065 -0.2794)
			(end 0.12065 -0.3048)
			(stroke
				(width 0.1)
				(type default)
			)
			(layer "F.Fab")
		)
		(fp_line
			(start 0.12065 -0.3048)
			(end 0.67945 -0.3048)
			(stroke
				(width 0.1)
				(type default)
			)
			(layer "F.Fab")
		)
		(fp_line
			(start 0.120396 0.3048)
			(end 0.120396 0.2794)
			(stroke
				(width 0.1)
				(type default)
			)
			(layer "F.Fab")
		)
		(fp_line
			(start 0.120396 0.2794)
			(end -0.12065 0.2794)
			(stroke
				(width 0.1)
				(type default)
			)
			(layer "F.Fab")
		)
		(fp_line
			(start -0.12065 0.3048)
			(end -0.67945 0.3048)
			(stroke
				(width 0.1)
				(type default)
			)
			(layer "F.Fab")
		)
		(fp_line
			(start -0.12065 0.2794)
			(end -0.12065 0.3048)
			(stroke
				(width 0.1)
				(type default)
			)
			(layer "F.Fab")
		)
		(fp_line
			(start -0.12065 -0.2794)
			(end 0.12065 -0.2794)
			(stroke
				(width 0.1)
				(type default)
			)
			(layer "F.Fab")
		)
		(fp_line
			(start -0.12065 -0.305054)
			(end -0.12065 -0.2794)
			(stroke
				(width 0.1)
				(type default)
			)
			(layer "F.Fab")
		)
		(fp_line
			(start -0.67945 0.3048)
			(end -0.67945 -0.305054)
			(stroke
				(width 0.1)
				(type default)
			)
			(layer "F.Fab")
		)
		(fp_line
			(start -0.67945 -0.305054)
			(end -0.12065 -0.305054)
			(stroke
				(width 0.1)
				(type default)
			)
			(layer "F.Fab")
		)
		(pad "1" smd circle
			(at -0.40005 0 180)
			(size 0 0)
			(layers "F.Cu" "F.Mask" "F.Paste")
			(net "P3V3_AUX")
		)
		(pad "2" smd circle
			(at 0.40005 0 180)
			(size 0 0)
			(layers "F.Cu" "F.Mask" "F.Paste")
			(net "IRQ_BMC_CPU_NMI_R1")
		)
	)
	(footprint ""
		(layer "F.Cu")
		(at 137.706354 -408.517344 -90)
		(property "Reference" "C1527"
			(at 0 0 270)
			(layer "F.SilkS")
			(hide yes)
			(effects
				(font
					(size 1.27 1.27)
				)
			)
		)
		(property "Value" ""
			(at 0 0 270)
			(layer "F.Fab")
			(effects
				(font
					(size 1.27 1.27)
				)
			)
		)
		(duplicate_pad_numbers_are_jumpers no)
		(fp_line
			(start -0.299974 0.150114)
			(end -0.299974 -0.150114)
			(stroke
				(width 0.1)
				(type default)
			)
			(layer "F.Fab")
		)
		(fp_line
			(start 0.299974 0.150114)
			(end -0.299974 0.150114)
			(stroke
				(width 0.1)
				(type default)
			)
			(layer "F.Fab")
		)
		(fp_line
			(start -0.299974 -0.150114)
			(end 0.299974 -0.150114)
			(stroke
				(width 0.1)
				(type default)
			)
			(layer "F.Fab")
		)
		(fp_line
			(start 0.299974 -0.150114)
			(end 0.299974 0.150114)
			(stroke
				(width 0.1)
				(type default)
			)
			(layer "F.Fab")
		)
		(pad "1" smd rect
			(at -0.2667 0 270)
			(size 0.3048 0.381)
			(layers "F.Cu" "F.Mask" "F.Paste")
			(net "P5E_CPU1_PE3_TX_C_DP<10>")
		)
		(pad "2" smd rect
			(at 0.2667 0 270)
			(size 0.3048 0.381)
			(layers "F.Cu" "F.Mask" "F.Paste")
			(net "P5E_CPU1_PE3_TX_DP<10>")
		)
	)
	(footprint ""
		(layer "F.Cu")
		(at 106.3244 -249.320558 -90)
		(property "Reference" "C303"
			(at 0 0 270)
			(layer "F.SilkS")
			(hide yes)
			(effects
				(font
					(size 1.27 1.27)
				)
			)
		)
		(property "Value" ""
			(at 0 0 270)
			(layer "F.Fab")
			(effects
				(font
					(size 1.27 1.27)
				)
			)
		)
		(duplicate_pad_numbers_are_jumpers no)
		(fp_line
			(start -0.7874 0.4064)
			(end -0.7874 -0.4064)
			(stroke
				(width 0.1524)
				(type default)
			)
			(layer "F.SilkS")
		)
		(fp_line
			(start 0.7874 0.4064)
			(end -0.7874 0.4064)
			(stroke
				(width 0.1524)
				(type default)
			)
			(layer "F.SilkS")
		)
		(fp_line
			(start -0.7874 -0.4064)
			(end 0.7874 -0.4064)
			(stroke
				(width 0.1524)
				(type default)
			)
			(layer "F.SilkS")
		)
		(fp_line
			(start 0.7874 -0.4064)
			(end 0.7874 0.4064)
			(stroke
				(width 0.1524)
				(type default)
			)
			(layer "F.SilkS")
		)
		(fp_line
			(start -0.67945 0.3048)
			(end -0.67945 -0.305054)
			(stroke
				(width 0.1)
				(type default)
			)
			(layer "F.Fab")
		)
		(fp_line
			(start -0.12065 0.3048)
			(end -0.67945 0.3048)
			(stroke
				(width 0.1)
				(type default)
			)
			(layer "F.Fab")
		)
		(fp_line
			(start 0.120396 0.3048)
			(end 0.120396 0.2794)
			(stroke
				(width 0.1)
				(type default)
			)
			(layer "F.Fab")
		)
		(fp_line
			(start 0.67945 0.3048)
			(end 0.120396 0.3048)
			(stroke
				(width 0.1)
				(type default)
			)
			(layer "F.Fab")
		)
		(fp_line
			(start -0.12065 0.2794)
			(end -0.12065 0.3048)
			(stroke
				(width 0.1)
				(type default)
			)
			(layer "F.Fab")
		)
		(fp_line
			(start 0.120396 0.2794)
			(end -0.12065 0.2794)
			(stroke
				(width 0.1)
				(type default)
			)
			(layer "F.Fab")
		)
		(fp_line
			(start -0.12065 -0.2794)
			(end 0.12065 -0.2794)
			(stroke
				(width 0.1)
				(type default)
			)
			(layer "F.Fab")
		)
		(fp_line
			(start 0.12065 -0.2794)
			(end 0.12065 -0.3048)
			(stroke
				(width 0.1)
				(type default)
			)
			(layer "F.Fab")
		)
		(fp_line
			(start 0.12065 -0.3048)
			(end 0.67945 -0.3048)
			(stroke
				(width 0.1)
				(type default)
			)
			(layer "F.Fab")
		)
		(fp_line
			(start 0.67945 -0.3048)
			(end 0.67945 0.3048)
			(stroke
				(width 0.1)
				(type default)
			)
			(layer "F.Fab")
		)
		(fp_line
			(start -0.67945 -0.305054)
			(end -0.12065 -0.305054)
			(stroke
				(width 0.1)
				(type default)
			)
			(layer "F.Fab")
		)
		(fp_line
			(start -0.12065 -0.305054)
			(end -0.12065 -0.2794)
			(stroke
				(width 0.1)
				(type default)
			)
			(layer "F.Fab")
		)
		(pad "1" smd circle
			(at -0.40005 0 270)
			(size 0 0)
			(layers "F.Cu" "F.Mask" "F.Paste")
			(net "PVCCIN_CPU1")
		)
		(pad "2" smd circle
			(at 0.40005 0 270)
			(size 0 0)
			(layers "F.Cu" "F.Mask" "F.Paste")
			(net "GND")
		)
	)
)
